#ISCELL
  pure_quanta quanta_title_block_c *
  *
#ISCELL
  standard offpage *
  page304_i1
#ISCELL
  logical_power universal_gnd *
  page304_i10
#CELL
  pure_quanta q_led *
  page304_i12
#ISCELL
  logical_power universal_power *
  page304_i14
#ISCELL
  logical_power universal_power *
  page304_i16
#ISCELL
  standard offpage *
  page304_i17
#ISCELL
  logical_power universal_gnd *
  page304_i19
#ISCELL
  standard offpage *
  page304_i2
#CELL
  pure_quanta q_led *
  page304_i20
#CELL
  pure_quanta q_led *
  page304_i21
#ISCELL
  logical_power universal_power *
  page304_i24
#ISCELL
  standard offpage *
  page304_i25
#ISCELL
  logical_power universal_power *
  page304_i26
#ISCELL
  logical_power universal_gnd *
  page304_i29
#ISCELL
  standard offpage *
  page304_i3
#CELL
  pure_quanta q_led *
  page304_i31
#CELL
  pure_quanta q_led *
  page304_i32
#ISCELL
  logical_power universal_power *
  page304_i35
#ISCELL
  logical_power universal_power *
  page304_i36
#CELL
  pure_quanta q_res *
  page304_i49
#ISCELL
  standard offpage *
  page304_i5
#CELL
  pure_quanta q_res *
  page304_i50
#CELL
  pure_quanta q_res *
  page304_i51
#CELL
  pure_quanta q_res *
  page304_i52
#CELL
  pure_quanta q_res *
  page304_i53
#CELL
  pure_quanta q_res *
  page304_i54
#ISCELL
  logical_power universal_power *
  page304_i55
#ISCELL
  logical_power universal_power *
  page304_i56
#CELL
  pure_quanta q_res *
  page304_i57
#CELL
  pure_quanta q_led *
  page304_i58
#ISCELL
  logical_power universal_gnd *
  page304_i59
#ISCELL
  logical_power universal_gnd *
  page304_i6
#ISCELL
  standard offpage *
  page304_i61
#CELL
  pure_quanta q_res *
  page304_i62
#CELL
  pure_quanta q_led *
  page304_i63
#ISCELL
  logical_power universal_gnd *
  page304_i64
#ISCELL
  standard offpage *
  page304_i66
#ISCELL
  logical_power universal_gnd *
  page304_i67
#CELL
  pure_quanta mosfet_nch_dual *
  page304_i68
#CELL
  pure_quanta mosfet_nch_dual *
  page304_i69
#CELL
  pure_quanta mosfet_nch_dual *
  page304_i70
#CELL
  pure_quanta mosfet_nch_dual *
  page304_i71
#CELL
  pure_quanta mosfet_nch_dual *
  page304_i72
#CELL
  pure_quanta mosfet_nch_dual *
  page304_i74
#CELL
  pure_quanta mosfet_nch_dual *
  page304_i75
#CELL
  pure_quanta mosfet_nch_dual *
  page304_i76
#ISCELL
  logical_power universal_gnd *
  page304_i8
#CELL
  pure_quanta q_led *
  page304_i9
